(kicad_pcb
	(version 20260206)
	(generator "pcbnew")
	(generator_version "10.0")
	(general
		(thickness 1.6)
		(legacy_teardrops no)
	)
	(paper "A4")
	(title_block
		(title "dpb — 14545-sa.0730WZS0815.brd")
		(comment 1 "Honey Badger (Wiwynn) / footprints 130-136 of 1066")
	)
	(layers
		(0 "F.Cu" signal "TOP")
		(4 "In1.Cu" signal "L2GND")
		(6 "In2.Cu" signal "L3")
		(8 "In3.Cu" signal "L4VCC")
		(10 "In4.Cu" signal "L5VCC")
		(12 "In5.Cu" signal "L6")
		(14 "In6.Cu" signal "L7GND")
		(2 "B.Cu" signal "BOTTOM")
		(9 "F.Adhes" user "F.Adhesive")
		(11 "B.Adhes" user "B.Adhesive")
		(13 "F.Paste" user "Package Geometry/Pastemask Top")
		(15 "B.Paste" user "Package Geometry/Pastemask Bottom")
		(5 "F.SilkS" user "Ref Des/Silkscreen Top")
		(7 "B.SilkS" user "Ref Des/Silkscreen Bottom")
		(1 "F.Mask" user "Board Geometry/Soldermask Top")
		(3 "B.Mask" user "Board Geometry/Soldermask Bottom")
		(17 "Dwgs.User" user "User.Drawings")
		(19 "Cmts.User" user "User.Comments")
		(21 "Eco1.User" user "User.Eco1")
		(23 "Eco2.User" user "User.Eco2")
		(25 "Edge.Cuts" user "Board Geometry/Outline")
		(27 "Margin" user)
		(31 "F.CrtYd" user "Package Geometry/Place Bound Top")
		(29 "B.CrtYd" user "Package Geometry/Place Bound Bottom")
		(35 "F.Fab" user "Ref Des/Assembly Top")
		(33 "B.Fab" user "Ref Des/Assembly Bottom")
	)
	(footprint ""
		(layer "F.Cu")
		(at 54.355746 -10.0457)
		(property "Reference" "PL3"
			(at 0 0 0)
			(layer "F.SilkS")
			(hide yes)
			(effects
				(font
					(size 1.27 1.27)
				)
			)
		)
		(property "Value" "BLM41PG600-GP"
			(at -3.690874 -7.441184 0)
			(unlocked yes)
			(layer "F.Fab")
			(hide yes)
			(effects
				(font
					(size 1.016 1.016)
					(thickness 0.1524)
				)
			)
		)
		(property "Device Type" "L451616H71"
			(at -3.690874 -5.917184 0)
			(unlocked yes)
			(layer "F.Fab")
			(hide yes)
			(effects
				(font
					(size 1.016 1.016)
					(thickness 0.1524)
				)
			)
		)
		(duplicate_pad_numbers_are_jumpers no)
		(fp_line
			(start -2.8702 -1.2954)
			(end -2.8702 1.2954)
			(stroke
				(width 0.1524)
				(type default)
			)
			(layer "F.SilkS")
		)
		(fp_line
			(start -2.8702 -1.2954)
			(end -2.8702 1.2954)
			(stroke
				(width 0.1524)
				(type default)
			)
			(layer "F.SilkS")
		)
		(fp_line
			(start -2.8702 1.2954)
			(end 2.8702 1.2954)
			(stroke
				(width 0.1524)
				(type default)
			)
			(layer "F.SilkS")
		)
		(fp_line
			(start -2.8702 1.2954)
			(end 2.8702 1.2954)
			(stroke
				(width 0.1524)
				(type default)
			)
			(layer "F.SilkS")
		)
		(fp_line
			(start 2.8702 -1.2954)
			(end -2.8702 -1.2954)
			(stroke
				(width 0.1524)
				(type default)
			)
			(layer "F.SilkS")
		)
		(fp_line
			(start 2.8702 -1.2954)
			(end -2.8702 -1.2954)
			(stroke
				(width 0.1524)
				(type default)
			)
			(layer "F.SilkS")
		)
		(fp_line
			(start 2.8702 1.2954)
			(end 2.8702 -1.2954)
			(stroke
				(width 0.1524)
				(type default)
			)
			(layer "F.SilkS")
		)
		(fp_line
			(start 2.8702 1.2954)
			(end 2.8702 -1.2954)
			(stroke
				(width 0.1524)
				(type default)
			)
			(layer "F.SilkS")
		)
		(fp_poly
			(pts
				(xy -2.8702 1.2954) (xy 2.8702 1.2954) (xy 2.8702 -1.2954) (xy -2.8702 -1.2954)
			)
			(stroke
				(width 0)
				(type default)
			)
			(fill no)
			(layer "F.CrtYd")
		)
		(fp_poly
			(pts
				(xy -2.8702 1.2954) (xy 2.8702 1.2954) (xy 2.8702 -1.2954) (xy -2.8702 -1.2954)
			)
			(stroke
				(width 0)
				(type default)
			)
			(fill no)
			(layer "F.Fab")
		)
		(pad "1" smd rect
			(at -1.9685 0)
			(size 1.3716 1.8796)
			(layers "F.Cu" "F.Mask" "F.Paste")
			(net "P12V")
		)
		(pad "2" smd rect
			(at 1.9685 0)
			(size 1.3716 1.8796)
			(layers "F.Cu" "F.Mask" "F.Paste")
			(net "P5VB_12VIN")
		)
	)
	(footprint ""
		(layer "F.Cu")
		(at 215.265 -70.3072 -90)
		(property "Reference" "R374"
			(at 0 0 270)
			(layer "F.SilkS")
			(hide yes)
			(effects
				(font
					(size 1.27 1.27)
				)
			)
		)
		(property "Value" "0R2J-2-GP"
			(at 0.064008 -3.993896 270)
			(unlocked yes)
			(layer "F.Fab")
			(hide yes)
			(effects
				(font
					(size 1.016 1.016)
					(thickness 0.1524)
				)
			)
		)
		(property "Device Type" "R402H16"
			(at 0.064008 -5.517896 270)
			(unlocked yes)
			(layer "F.Fab")
			(hide yes)
			(effects
				(font
					(size 1.016 1.016)
					(thickness 0.1524)
				)
			)
		)
		(duplicate_pad_numbers_are_jumpers no)
		(fp_line
			(start -0.508 -0.9398)
			(end -0.508 0.9398)
			(stroke
				(width 0.1524)
				(type default)
			)
			(layer "F.SilkS")
		)
		(fp_line
			(start 0.508 -0.9398)
			(end -0.508 -0.9398)
			(stroke
				(width 0.1524)
				(type default)
			)
			(layer "F.SilkS")
		)
		(fp_rect
			(start -0.508 0.9398)
			(end 0.508 -0.9398)
			(stroke
				(width 0)
				(type default)
			)
			(fill no)
			(layer "F.CrtYd")
		)
		(fp_rect
			(start -0.508 0.9398)
			(end 0.508 -0.9398)
			(stroke
				(width 0)
				(type default)
			)
			(fill no)
			(layer "F.Fab")
		)
		(pad "1" smd custom
			(at 0 -0.4445 270)
			(size 0.1397 0.1397)
			(layers "F.Cu" "F.Mask" "F.Paste")
			(net "HDD_PRSNT_NET4")
			(options
				(clearance outline)
				(anchor circle)
			)
			(primitives
				(gr_poly
					(pts
						(arc
							(start -0.1778 -0.2794)
							(mid -0.249642 -0.249642)
							(end -0.2794 -0.1778)
						)
						(arc
							(start -0.2794 0.1778)
							(mid -0.249642 0.249642)
							(end -0.1778 0.2794)
						)
						(arc
							(start 0.1778 0.2794)
							(mid 0.249642 0.249642)
							(end 0.2794 0.1778)
						)
						(arc
							(start 0.2794 -0.1778)
							(mid 0.249642 -0.249642)
							(end 0.1778 -0.2794)
						)
					)
					(width 0)
					(fill yes)
				)
			)
		)
		(pad "2" smd custom
			(at 0 0.4445 270)
			(size 0.1397 0.1397)
			(layers "F.Cu" "F.Mask" "F.Paste")
			(net "HDD4_LED_B")
			(options
				(clearance outline)
				(anchor circle)
			)
			(primitives
				(gr_poly
					(pts
						(arc
							(start -0.1778 -0.2794)
							(mid -0.249642 -0.249642)
							(end -0.2794 -0.1778)
						)
						(arc
							(start -0.2794 0.1778)
							(mid -0.249642 0.249642)
							(end -0.1778 0.2794)
						)
						(arc
							(start 0.1778 0.2794)
							(mid 0.249642 0.249642)
							(end 0.2794 0.1778)
						)
						(arc
							(start 0.2794 -0.1778)
							(mid 0.249642 -0.249642)
							(end 0.1778 -0.2794)
						)
					)
					(width 0)
					(fill yes)
				)
			)
		)
	)
	(footprint ""
		(layer "F.Cu")
		(at 45.339 -431.673 180)
		(property "Reference" "C374"
			(at 0 0 180)
			(layer "F.SilkS")
			(hide yes)
			(effects
				(font
					(size 1.27 1.27)
				)
			)
		)
		(property "Value" "SCD033U25V2KX-GP"
			(at 1.1811 -2.7051 180)
			(unlocked yes)
			(layer "F.Fab")
			(hide yes)
			(effects
				(font
					(size 1.016 1.016)
					(thickness 0.1524)
				)
			)
		)
		(property "Device Type" "C402H22"
			(at 1.1811 -4.2291 180)
			(unlocked yes)
			(layer "F.Fab")
			(hide yes)
			(effects
				(font
					(size 1.016 1.016)
					(thickness 0.1524)
				)
			)
		)
		(duplicate_pad_numbers_are_jumpers no)
		(fp_rect
			(start -0.4318 0.9525)
			(end 0.4318 -0.9525)
			(stroke
				(width 0)
				(type default)
			)
			(fill no)
			(layer "F.CrtYd")
		)
		(fp_rect
			(start -0.4318 0.9525)
			(end 0.4318 -0.9525)
			(stroke
				(width 0)
				(type default)
			)
			(fill no)
			(layer "F.Fab")
		)
		(pad "1" smd custom
			(at 0 -0.4445 180)
			(size 0.1524 0.1524)
			(layers "F.Cu" "F.Mask" "F.Paste")
			(net "SW_HDD10_P")
			(options
				(clearance outline)
				(anchor circle)
			)
			(primitives
				(gr_poly
					(pts
						(arc
							(start 0.3048 -0.2032)
							(mid 0.275042 -0.275042)
							(end 0.2032 -0.3048)
						)
						(arc
							(start -0.2032 -0.3048)
							(mid -0.275042 -0.275042)
							(end -0.3048 -0.2032)
						)
						(arc
							(start -0.3048 0.2032)
							(mid -0.275042 0.275042)
							(end -0.2032 0.3048)
						)
						(arc
							(start 0.2032 0.3048)
							(mid 0.275042 0.275042)
							(end 0.3048 0.2032)
						)
					)
					(width 0)
					(fill yes)
				)
			)
		)
		(pad "2" smd custom
			(at 0 0.4445 180)
			(size 0.1524 0.1524)
			(layers "F.Cu" "F.Mask" "F.Paste")
			(net "GND")
			(options
				(clearance outline)
				(anchor circle)
			)
			(primitives
				(gr_poly
					(pts
						(arc
							(start 0.3048 -0.2032)
							(mid 0.275042 -0.275042)
							(end 0.2032 -0.3048)
						)
						(arc
							(start -0.2032 -0.3048)
							(mid -0.275042 -0.275042)
							(end -0.3048 -0.2032)
						)
						(arc
							(start -0.3048 0.2032)
							(mid -0.275042 0.275042)
							(end -0.2032 0.3048)
						)
						(arc
							(start 0.2032 0.3048)
							(mid 0.275042 0.275042)
							(end 0.3048 0.2032)
						)
					)
					(width 0)
					(fill yes)
				)
			)
		)
	)
	(footprint ""
		(layer "F.Cu")
		(at 238.886746 -27.9527 180)
		(property "Reference" "PR16"
			(at 0 0 180)
			(layer "F.SilkS")
			(hide yes)
			(effects
				(font
					(size 1.27 1.27)
				)
			)
		)
		(property "Value" "0R2J-2-GP"
			(at 0.064008 -3.993896 180)
			(unlocked yes)
			(layer "F.Fab")
			(hide yes)
			(effects
				(font
					(size 1.016 1.016)
					(thickness 0.1524)
				)
			)
		)
		(property "Device Type" "R402H16"
			(at 0.064008 -5.517896 180)
			(unlocked yes)
			(layer "F.Fab")
			(hide yes)
			(effects
				(font
					(size 1.016 1.016)
					(thickness 0.1524)
				)
			)
		)
		(duplicate_pad_numbers_are_jumpers no)
		(fp_line
			(start 0.508 -0.9398)
			(end -0.508 -0.9398)
			(stroke
				(width 0.1524)
				(type default)
			)
			(layer "F.SilkS")
		)
		(fp_line
			(start -0.508 -0.9398)
			(end -0.508 0.9398)
			(stroke
				(width 0.1524)
				(type default)
			)
			(layer "F.SilkS")
		)
		(fp_rect
			(start -0.508 0.9398)
			(end 0.508 -0.9398)
			(stroke
				(width 0)
				(type default)
			)
			(fill no)
			(layer "F.CrtYd")
		)
		(fp_rect
			(start -0.508 0.9398)
			(end 0.508 -0.9398)
			(stroke
				(width 0)
				(type default)
			)
			(fill no)
			(layer "F.Fab")
		)
		(pad "1" smd custom
			(at 0 -0.4445 180)
			(size 0.1397 0.1397)
			(layers "F.Cu" "F.Mask" "F.Paste")
			(net "P5VA_RF")
			(options
				(clearance outline)
				(anchor circle)
			)
			(primitives
				(gr_poly
					(pts
						(arc
							(start -0.1778 -0.2794)
							(mid -0.249642 -0.249642)
							(end -0.2794 -0.1778)
						)
						(arc
							(start -0.2794 0.1778)
							(mid -0.249642 0.249642)
							(end -0.1778 0.2794)
						)
						(arc
							(start 0.1778 0.2794)
							(mid 0.249642 0.249642)
							(end 0.2794 0.1778)
						)
						(arc
							(start 0.2794 -0.1778)
							(mid 0.249642 -0.249642)
							(end 0.1778 -0.2794)
						)
					)
					(width 0)
					(fill yes)
				)
			)
		)
		(pad "2" smd custom
			(at 0 0.4445 180)
			(size 0.1397 0.1397)
			(layers "F.Cu" "F.Mask" "F.Paste")
			(net "P5VA_AGND")
			(options
				(clearance outline)
				(anchor circle)
			)
			(primitives
				(gr_poly
					(pts
						(arc
							(start -0.1778 -0.2794)
							(mid -0.249642 -0.249642)
							(end -0.2794 -0.1778)
						)
						(arc
							(start -0.2794 0.1778)
							(mid -0.249642 0.249642)
							(end -0.1778 0.2794)
						)
						(arc
							(start 0.1778 0.2794)
							(mid 0.249642 0.249642)
							(end 0.2794 0.1778)
						)
						(arc
							(start 0.2794 -0.1778)
							(mid 0.249642 -0.249642)
							(end 0.1778 -0.2794)
						)
					)
					(width 0)
					(fill yes)
				)
			)
		)
	)
	(footprint ""
		(layer "F.Cu")
		(at 232.790746 -27.9527 180)
		(property "Reference" "PR3"
			(at 0 0 180)
			(layer "F.SilkS")
			(hide yes)
			(effects
				(font
					(size 1.27 1.27)
				)
			)
		)
		(property "Value" "2K49R2F-GP"
			(at 0.064008 -3.993896 180)
			(unlocked yes)
			(layer "F.Fab")
			(hide yes)
			(effects
				(font
					(size 1.016 1.016)
					(thickness 0.1524)
				)
			)
		)
		(property "Device Type" "R402H16"
			(at 0.064008 -5.517896 180)
			(unlocked yes)
			(layer "F.Fab")
			(hide yes)
			(effects
				(font
					(size 1.016 1.016)
					(thickness 0.1524)
				)
			)
		)
		(duplicate_pad_numbers_are_jumpers no)
		(fp_line
			(start 0.508 -0.9398)
			(end -0.508 -0.9398)
			(stroke
				(width 0.1524)
				(type default)
			)
			(layer "F.SilkS")
		)
		(fp_line
			(start -0.508 -0.9398)
			(end -0.508 0.9398)
			(stroke
				(width 0.1524)
				(type default)
			)
			(layer "F.SilkS")
		)
		(fp_rect
			(start -0.508 0.9398)
			(end 0.508 -0.9398)
			(stroke
				(width 0)
				(type default)
			)
			(fill no)
			(layer "F.CrtYd")
		)
		(fp_rect
			(start -0.508 0.9398)
			(end 0.508 -0.9398)
			(stroke
				(width 0)
				(type default)
			)
			(fill no)
			(layer "F.Fab")
		)
		(pad "1" smd custom
			(at 0 -0.4445 180)
			(size 0.1397 0.1397)
			(layers "F.Cu" "F.Mask" "F.Paste")
			(net "P5VA_EN")
			(options
				(clearance outline)
				(anchor circle)
			)
			(primitives
				(gr_poly
					(pts
						(arc
							(start -0.1778 -0.2794)
							(mid -0.249642 -0.249642)
							(end -0.2794 -0.1778)
						)
						(arc
							(start -0.2794 0.1778)
							(mid -0.249642 0.249642)
							(end -0.1778 0.2794)
						)
						(arc
							(start 0.1778 0.2794)
							(mid 0.249642 0.249642)
							(end 0.2794 0.1778)
						)
						(arc
							(start 0.2794 -0.1778)
							(mid 0.249642 -0.249642)
							(end 0.1778 -0.2794)
						)
					)
					(width 0)
					(fill yes)
				)
			)
		)
		(pad "2" smd custom
			(at 0 0.4445 180)
			(size 0.1397 0.1397)
			(layers "F.Cu" "F.Mask" "F.Paste")
			(net "GND")
			(options
				(clearance outline)
				(anchor circle)
			)
			(primitives
				(gr_poly
					(pts
						(arc
							(start -0.1778 -0.2794)
							(mid -0.249642 -0.249642)
							(end -0.2794 -0.1778)
						)
						(arc
							(start -0.2794 0.1778)
							(mid -0.249642 0.249642)
							(end -0.1778 0.2794)
						)
						(arc
							(start 0.1778 0.2794)
							(mid 0.249642 0.249642)
							(end 0.2794 0.1778)
						)
						(arc
							(start 0.2794 -0.1778)
							(mid 0.249642 -0.249642)
							(end 0.1778 -0.2794)
						)
					)
					(width 0)
					(fill yes)
				)
			)
		)
	)
	(footprint ""
		(layer "F.Cu")
		(at 28.6766 -401.955 90)
		(property "Reference" "TC1"
			(at 0 0 90)
			(layer "F.SilkS")
			(hide yes)
			(effects
				(font
					(size 1.27 1.27)
				)
			)
		)
		(property "Value" "ST15U25VDM-1-GP"
			(at 0 -9.6012 90)
			(unlocked yes)
			(layer "F.Fab")
			(hide yes)
			(effects
				(font
					(size 1.016 1.016)
					(thickness 0.1524)
				)
			)
		)
		(property "Device Type" "CT7343H79"
			(at 0 -11.1252 90)
			(unlocked yes)
			(layer "F.Fab")
			(hide yes)
			(effects
				(font
					(size 1.016 1.016)
					(thickness 0.1524)
				)
			)
		)
		(duplicate_pad_numbers_are_jumpers no)
		(fp_line
			(start 2.286 -4.8768)
			(end -2.286 -4.8768)
			(stroke
				(width 0.1524)
				(type default)
			)
			(layer "F.SilkS")
		)
		(fp_line
			(start -2.286 -4.8768)
			(end -2.286 -2.032)
			(stroke
				(width 0.1524)
				(type default)
			)
			(layer "F.SilkS")
		)
		(fp_line
			(start 2.1082 -4.699)
			(end -2.1082 -4.699)
			(stroke
				(width 0.508)
				(type default)
			)
			(layer "F.SilkS")
		)
		(fp_line
			(start 2.286 -2.032)
			(end 2.286 -4.8768)
			(stroke
				(width 0.1524)
				(type default)
			)
			(layer "F.SilkS")
		)
		(fp_line
			(start 2.286 2.032)
			(end 2.286 4.8768)
			(stroke
				(width 0.1524)
				(type default)
			)
			(layer "F.SilkS")
		)
		(fp_line
			(start 2.286 4.8768)
			(end -2.286 4.8768)
			(stroke
				(width 0.1524)
				(type default)
			)
			(layer "F.SilkS")
		)
		(fp_line
			(start -2.286 4.8768)
			(end -2.286 2.032)
			(stroke
				(width 0.1524)
				(type default)
			)
			(layer "F.SilkS")
		)
		(fp_rect
			(start -2.1463 3.6449)
			(end 2.1463 -3.6449)
			(stroke
				(width 0)
				(type default)
			)
			(fill no)
			(layer "F.CrtYd")
		)
		(fp_poly
			(pts
				(xy -2.54 4.953) (xy -2.54 4.2926) (xy -3.81 4.2926) (xy -3.81 -4.2926) (xy -2.54 -4.2926) (xy -2.54 -4.953)
				(xy 2.54 -4.953) (xy 2.54 -4.2926) (xy 3.81 -4.2926) (xy 3.81 -1.6256) (xy 2.1463 -1.6256) (xy 2.1463 -3.6449)
				(xy -2.1463 -3.6449) (xy -2.1463 3.6449) (xy 2.1463 3.6449) (xy 2.1463 -1.6129) (xy 3.81 -1.6129)
				(xy 3.81 4.2926) (xy 2.54 4.2926) (xy 2.54 4.953)
			)
			(stroke
				(width 0)
				(type default)
			)
			(fill no)
			(layer "F.CrtYd")
		)
		(fp_rect
			(start 2.54 4.2926)
			(end 3.81 -4.2926)
			(stroke
				(width 0)
				(type default)
			)
			(fill no)
			(layer "F.Fab")
		)
		(fp_rect
			(start -3.81 4.2926)
			(end -2.54 -4.2926)
			(stroke
				(width 0)
				(type default)
			)
			(fill no)
			(layer "F.Fab")
		)
		(fp_rect
			(start -2.54 4.953)
			(end 2.54 -4.953)
			(stroke
				(width 0)
				(type default)
			)
			(fill no)
			(layer "F.Fab")
		)
		(pad "1" smd rect
			(at 0 -3.1496 90)
			(size 2.413 2.286)
			(layers "F.Cu" "F.Mask" "F.Paste")
			(net "P12V")
		)
		(pad "2" smd rect
			(at 0 3.1496 90)
			(size 2.413 2.286)
			(layers "F.Cu" "F.Mask" "F.Paste")
			(net "GND")
		)
		(zone
			(layer "F.Cu")
			(hatch none 0.5)
			(connect_pads
				(clearance 0)
			)
			(min_thickness 0.25)
			(keepout
				(tracks allowed)
				(vias not_allowed)
				(pads allowed)
				(copperpour not_allowed)
				(footprints allowed)
			)
			(placement
				(enabled no)
				(sheetname "")
			)
			(fill
				(thermal_gap 0.5)
				(thermal_bridge_width 0.5)
				(island_removal_mode 0)
			)
			(polygon
				(pts
					(xy 26.9875 -403.4663) (xy 24.0792 -403.4663) (xy 24.0792 -400.4437) (xy 26.9748 -400.4437) (xy 27.305 -400.4437)
					(xy 27.305 -403.4663)
				)
			)
		)
		(zone
			(layer "F.Cu")
			(hatch none 0.5)
			(connect_pads
				(clearance 0)
			)
			(min_thickness 0.25)
			(keepout
				(tracks allowed)
				(vias not_allowed)
				(pads allowed)
				(copperpour not_allowed)
				(footprints allowed)
			)
			(placement
				(enabled no)
				(sheetname "")
			)
			(fill
				(thermal_gap 0.5)
				(thermal_bridge_width 0.5)
				(island_removal_mode 0)
			)
			(polygon
				(pts
					(xy 33.274 -400.4437) (xy 33.274 -403.4663) (xy 30.3784 -403.4663) (xy 30.0482 -403.4663) (xy 30.0482 -400.4437)
					(xy 30.3784 -400.4437)
				)
			)
		)
	)
	(footprint ""
		(layer "F.Cu")
		(at 217.483182 -291.310568 180)
		(property "Reference" "C145"
			(at 0 0 180)
			(layer "F.SilkS")
			(hide yes)
			(effects
				(font
					(size 1.27 1.27)
				)
			)
		)
		(property "Value" "SC10U25V6KX-1GP"
			(at -0.0762 -5.1308 180)
			(unlocked yes)
			(layer "F.Fab")
			(hide yes)
			(effects
				(font
					(size 1.016 1.016)
					(thickness 0.1524)
				)
			)
		)
		(property "Device Type" "C1206H71"
			(at -0.127 -6.6548 180)
			(unlocked yes)
			(layer "F.Fab")
			(hide yes)
			(effects
				(font
					(size 1.016 1.016)
					(thickness 0.1524)
				)
			)
		)
		(duplicate_pad_numbers_are_jumpers no)
		(fp_line
			(start 1.016 2.2352)
			(end -1.016 2.2352)
			(stroke
				(width 0.1524)
				(type default)
			)
			(layer "F.SilkS")
		)
		(fp_line
			(start 1.016 0.8382)
			(end 1.016 2.2352)
			(stroke
				(width 0.1524)
				(type default)
			)
			(layer "F.SilkS")
		)
		(fp_line
			(start 1.016 -2.2352)
			(end 1.016 -0.8382)
			(stroke
				(width 0.1524)
				(type default)
			)
			(layer "F.SilkS")
		)
		(fp_line
			(start -1.016 2.2352)
			(end -1.016 0.8382)
			(stroke
				(width 0.1524)
				(type default)
			)
			(layer "F.SilkS")
		)
		(fp_line
			(start -1.016 -0.8382)
			(end -1.016 -2.2352)
			(stroke
				(width 0.1524)
				(type default)
			)
			(layer "F.SilkS")
		)
		(fp_line
			(start -1.016 -2.2352)
			(end 1.016 -2.2352)
			(stroke
				(width 0.1524)
				(type default)
			)
			(layer "F.SilkS")
		)
		(fp_rect
			(start -1.0922 2.3114)
			(end 1.0922 -2.3114)
			(stroke
				(width 0)
				(type default)
			)
			(fill no)
			(layer "F.CrtYd")
		)
		(fp_poly
			(pts
				(xy 1.0922 -2.3114) (xy 1.0922 2.3114) (xy -1.0922 2.3114) (xy -1.0922 -2.3114)
			)
			(stroke
				(width 0)
				(type default)
			)
			(fill no)
			(layer "F.Fab")
		)
		(pad "1" smd rect
			(at 0 -1.397 180)
			(size 1.651 1.27)
			(layers "F.Cu" "F.Mask" "F.Paste")
			(net "P12V_HDD2")
		)
		(pad "2" smd rect
			(at 0 1.397 180)
			(size 1.651 1.27)
			(layers "F.Cu" "F.Mask" "F.Paste")
			(net "GND")
		)
	)
)
